# T6G (Grand Teton) — schematic netlist excerpt (pin names and nets, part order shuffled) for the footprints in the layout excerpt that follows; sources: Cadence DE-HDL packaged netlist, KiCad conversion of 04192023_DAF0TMB3IC0_F0TG_MB_C_brd_V02_OCP.brd

PR55  Q_RES  1K 1% CHIP  pkg 0402LF  page 200 : A = P3V3_AUX ; B = PVDDIO_P0_EN_G
PR503  Q_RES  1.5 1% EMPTY  pkg 0402LF  page 198 : A = SW_PVDDCR_SOC_P0_SW2_RC ; B = GND

(kicad_pcb
	(version 20260206)
	(generator "pcbnew")
	(generator_version "10.0")
	(general
		(thickness 1.6)
		(legacy_teardrops no)
	)
	(paper "A4")
	(title_block
		(title "04192023_DAF0TMB3IC0_F0TG_MB_C_brd_V02_OCP.brd")
		(comment 1 "Grand Teton / footprints 2013-2014 of 8354")
	)
	(layers
		(0 "F.Cu" signal "TOP")
		(4 "In1.Cu" signal "GND")
		(6 "In2.Cu" signal "IN1")
		(8 "In3.Cu" signal "GND1")
		(10 "In4.Cu" signal "IN2")
		(12 "In5.Cu" signal "GND2")
		(14 "In6.Cu" signal "IN3")
		(16 "In7.Cu" signal "GND3")
		(18 "In8.Cu" signal "VCC")
		(20 "In9.Cu" signal "VCC1")
		(22 "In10.Cu" signal "GND4")
		(24 "In11.Cu" signal "IN4")
		(26 "In12.Cu" signal "GND5")
		(28 "In13.Cu" signal "IN5")
		(30 "In14.Cu" signal "GND6")
		(32 "In15.Cu" signal "IN6")
		(34 "In16.Cu" signal "GND7")
		(2 "B.Cu" signal "BOTTOM")
		(9 "F.Adhes" user "F.Adhesive")
		(11 "B.Adhes" user "B.Adhesive")
		(13 "F.Paste" user "Package Geometry/Pastemask Top")
		(15 "B.Paste" user "Package Geometry/Pastemask Bottom")
		(5 "F.SilkS" user "Ref Des/Silkscreen Top")
		(7 "B.SilkS" user "Ref Des/Silkscreen Bottom")
		(1 "F.Mask" user "Board Geometry/Soldermask Top")
		(3 "B.Mask" user "Board Geometry/Soldermask Bottom")
		(17 "Dwgs.User" user "User.Drawings")
		(19 "Cmts.User" user "User.Comments")
		(21 "Eco1.User" user "User.Eco1")
		(23 "Eco2.User" user "User.Eco2")
		(25 "Edge.Cuts" user "Board Geometry/Outline")
		(27 "Margin" user)
		(31 "F.CrtYd" user "Package Geometry/Place Bound Top")
		(29 "B.CrtYd" user "Package Geometry/Place Bound Bottom")
		(35 "F.Fab" user "Ref Des/Assembly Top")
		(33 "B.Fab" user "Ref Des/Assembly Bottom")
	)
	(footprint ""
		(layer "F.Cu")
		(at 295.09085 -369.375436 180)
		(property "Reference" "PR55"
			(at 0 0 180)
			(layer "F.SilkS")
			(hide yes)
			(effects
				(font
					(size 1.27 1.27)
				)
			)
		)
		(property "Value" ""
			(at 0 0 180)
			(layer "F.Fab")
			(effects
				(font
					(size 1.27 1.27)
				)
			)
		)
		(duplicate_pad_numbers_are_jumpers no)
		(fp_line
			(start 0.7874 0.4064)
			(end -0.7874 0.4064)
			(stroke
				(width 0.1524)
				(type default)
			)
			(layer "F.SilkS")
		)
		(fp_line
			(start 0.7874 -0.4064)
			(end 0.7874 0.4064)
			(stroke
				(width 0.1524)
				(type default)
			)
			(layer "F.SilkS")
		)
		(fp_line
			(start -0.7874 0.4064)
			(end -0.7874 -0.4064)
			(stroke
				(width 0.1524)
				(type default)
			)
			(layer "F.SilkS")
		)
		(fp_line
			(start -0.7874 -0.4064)
			(end 0.7874 -0.4064)
			(stroke
				(width 0.1524)
				(type default)
			)
			(layer "F.SilkS")
		)
		(fp_line
			(start 0.67945 0.3048)
			(end 0.120396 0.3048)
			(stroke
				(width 0.1)
				(type default)
			)
			(layer "F.Fab")
		)
		(fp_line
			(start 0.67945 -0.3048)
			(end 0.67945 0.3048)
			(stroke
				(width 0.1)
				(type default)
			)
			(layer "F.Fab")
		)
		(fp_line
			(start 0.12065 -0.2794)
			(end 0.12065 -0.3048)
			(stroke
				(width 0.1)
				(type default)
			)
			(layer "F.Fab")
		)
		(fp_line
			(start 0.12065 -0.3048)
			(end 0.67945 -0.3048)
			(stroke
				(width 0.1)
				(type default)
			)
			(layer "F.Fab")
		)
		(fp_line
			(start 0.120396 0.3048)
			(end 0.120396 0.2794)
			(stroke
				(width 0.1)
				(type default)
			)
			(layer "F.Fab")
		)
		(fp_line
			(start 0.120396 0.2794)
			(end -0.12065 0.2794)
			(stroke
				(width 0.1)
				(type default)
			)
			(layer "F.Fab")
		)
		(fp_line
			(start -0.12065 0.3048)
			(end -0.67945 0.3048)
			(stroke
				(width 0.1)
				(type default)
			)
			(layer "F.Fab")
		)
		(fp_line
			(start -0.12065 0.2794)
			(end -0.12065 0.3048)
			(stroke
				(width 0.1)
				(type default)
			)
			(layer "F.Fab")
		)
		(fp_line
			(start -0.12065 -0.2794)
			(end 0.12065 -0.2794)
			(stroke
				(width 0.1)
				(type default)
			)
			(layer "F.Fab")
		)
		(fp_line
			(start -0.12065 -0.305054)
			(end -0.12065 -0.2794)
			(stroke
				(width 0.1)
				(type default)
			)
			(layer "F.Fab")
		)
		(fp_line
			(start -0.67945 0.3048)
			(end -0.67945 -0.305054)
			(stroke
				(width 0.1)
				(type default)
			)
			(layer "F.Fab")
		)
		(fp_line
			(start -0.67945 -0.305054)
			(end -0.12065 -0.305054)
			(stroke
				(width 0.1)
				(type default)
			)
			(layer "F.Fab")
		)
		(pad "1" smd circle
			(at -0.40005 0 180)
			(size 0 0)
			(layers "F.Cu" "F.Mask" "F.Paste")
			(net "P3V3_AUX")
		)
		(pad "2" smd circle
			(at 0.40005 0 180)
			(size 0 0)
			(layers "F.Cu" "F.Mask" "F.Paste")
			(net "PVDDIO_P0_EN_G")
		)
	)
	(footprint ""
		(layer "F.Cu")
		(at 409.824936 -170.328082 -90)
		(property "Reference" "PR503"
			(at 0 0 270)
			(layer "F.SilkS")
			(hide yes)
			(effects
				(font
					(size 1.27 1.27)
				)
			)
		)
		(property "Value" ""
			(at 0 0 270)
			(layer "F.Fab")
			(effects
				(font
					(size 1.27 1.27)
				)
			)
		)
		(duplicate_pad_numbers_are_jumpers no)
		(fp_line
			(start -0.7874 0.4064)
			(end -0.7874 -0.4064)
			(stroke
				(width 0.1524)
				(type default)
			)
			(layer "F.SilkS")
		)
		(fp_line
			(start 0.7874 0.4064)
			(end -0.7874 0.4064)
			(stroke
				(width 0.1524)
				(type default)
			)
			(layer "F.SilkS")
		)
		(fp_line
			(start -0.7874 -0.4064)
			(end 0.7874 -0.4064)
			(stroke
				(width 0.1524)
				(type default)
			)
			(layer "F.SilkS")
		)
		(fp_line
			(start 0.7874 -0.4064)
			(end 0.7874 0.4064)
			(stroke
				(width 0.1524)
				(type default)
			)
			(layer "F.SilkS")
		)
		(fp_line
			(start -0.67945 0.3048)
			(end -0.67945 -0.305054)
			(stroke
				(width 0.1)
				(type default)
			)
			(layer "F.Fab")
		)
		(fp_line
			(start -0.12065 0.3048)
			(end -0.67945 0.3048)
			(stroke
				(width 0.1)
				(type default)
			)
			(layer "F.Fab")
		)
		(fp_line
			(start 0.120396 0.3048)
			(end 0.120396 0.2794)
			(stroke
				(width 0.1)
				(type default)
			)
			(layer "F.Fab")
		)
		(fp_line
			(start 0.67945 0.3048)
			(end 0.120396 0.3048)
			(stroke
				(width 0.1)
				(type default)
			)
			(layer "F.Fab")
		)
		(fp_line
			(start -0.12065 0.2794)
			(end -0.12065 0.3048)
			(stroke
				(width 0.1)
				(type default)
			)
			(layer "F.Fab")
		)
		(fp_line
			(start 0.120396 0.2794)
			(end -0.12065 0.2794)
			(stroke
				(width 0.1)
				(type default)
			)
			(layer "F.Fab")
		)
		(fp_line
			(start -0.12065 -0.2794)
			(end 0.12065 -0.2794)
			(stroke
				(width 0.1)
				(type default)
			)
			(layer "F.Fab")
		)
		(fp_line
			(start 0.12065 -0.2794)
			(end 0.12065 -0.3048)
			(stroke
				(width 0.1)
				(type default)
			)
			(layer "F.Fab")
		)
		(fp_line
			(start 0.12065 -0.3048)
			(end 0.67945 -0.3048)
			(stroke
				(width 0.1)
				(type default)
			)
			(layer "F.Fab")
		)
		(fp_line
			(start 0.67945 -0.3048)
			(end 0.67945 0.3048)
			(stroke
				(width 0.1)
				(type default)
			)
			(layer "F.Fab")
		)
		(fp_line
			(start -0.67945 -0.305054)
			(end -0.12065 -0.305054)
			(stroke
				(width 0.1)
				(type default)
			)
			(layer "F.Fab")
		)
		(fp_line
			(start -0.12065 -0.305054)
			(end -0.12065 -0.2794)
			(stroke
				(width 0.1)
				(type default)
			)
			(layer "F.Fab")
		)
		(pad "1" smd circle
			(at -0.40005 0 270)
			(size 0 0)
			(layers "F.Cu" "F.Mask" "F.Paste")
			(net "SW_PVDDCR_SOC_P0_SW2_RC")
		)
		(pad "2" smd circle
			(at 0.40005 0 270)
			(size 0 0)
			(layers "F.Cu" "F.Mask" "F.Paste")
			(net "GND")
		)
	)
)
